(kicad_pcb
	(version 20260206)
	(generator "pcbnew")
	(generator_version "10.0")
	(general
		(thickness 1.6)
		(legacy_teardrops no)
	)
	(paper "A4")
	(title_block
		(title "Wiwynn_Tioga_Pass_MB.brd")
		(comment 1 "Tioga Pass / footprints 3419-3426 of 4770")
	)
	(layers
		(0 "F.Cu" signal "TOP")
		(4 "In1.Cu" signal "L2GND")
		(6 "In2.Cu" signal "L3")
		(8 "In3.Cu" signal "L4GND")
		(10 "In4.Cu" signal "L5")
		(12 "In5.Cu" signal "L6GND")
		(14 "In6.Cu" signal "L7VCC")
		(16 "In7.Cu" signal "L8VCC")
		(18 "In8.Cu" signal "L9GND")
		(20 "In9.Cu" signal "L10")
		(22 "In10.Cu" signal "L11GND")
		(24 "In11.Cu" signal "L12")
		(26 "In12.Cu" signal "L13GND")
		(2 "B.Cu" signal "BOTTOM")
		(9 "F.Adhes" user "F.Adhesive")
		(11 "B.Adhes" user "B.Adhesive")
		(13 "F.Paste" user "Package Geometry/Pastemask Top")
		(15 "B.Paste" user "Package Geometry/Pastemask Bottom")
		(5 "F.SilkS" user "Ref Des/Silkscreen Top")
		(7 "B.SilkS" user "Ref Des/Silkscreen Bottom")
		(1 "F.Mask" user "Board Geometry/Soldermask Top")
		(3 "B.Mask" user "Board Geometry/Soldermask Bottom")
		(17 "Dwgs.User" user "User.Drawings")
		(19 "Cmts.User" user "User.Comments")
		(21 "Eco1.User" user "User.Eco1")
		(23 "Eco2.User" user "User.Eco2")
		(25 "Edge.Cuts" user "Board Geometry/Outline")
		(27 "Margin" user)
		(31 "F.CrtYd" user "Package Geometry/Place Bound Top")
		(29 "B.CrtYd" user "Package Geometry/Place Bound Bottom")
		(35 "F.Fab" user "Ref Des/Assembly Top")
		(33 "B.Fab" user "Ref Des/Assembly Bottom")
	)
	(footprint ""
		(layer "B.Cu")
		(at 269.559532 -12.954 90)
		(property "Reference" "C5G47"
			(at -1.14681 0.76708 180)
			(unlocked yes)
			(layer "B.SilkS")
			(effects
				(font
					(size 0.7874 0.5842)
					(thickness 0.1524)
				)
				(justify mirror)
			)
		)
		(property "Value" ""
			(at 0 0 90)
			(layer "B.Fab")
			(effects
				(font
					(size 1.27 1.27)
				)
				(justify mirror)
			)
		)
		(duplicate_pad_numbers_are_jumpers no)
		(fp_rect
			(start -0.4953 -0.2032)
			(end 0.4953 1.6002)
			(stroke
				(width 0)
				(type default)
			)
			(fill no)
			(layer "B.CrtYd")
		)
		(fp_line
			(start 0.4953 -0.2032)
			(end -0.4953 -0.2032)
			(stroke
				(width 0.1)
				(type default)
			)
			(layer "B.Fab")
		)
		(fp_line
			(start -0.4953 -0.2032)
			(end -0.4953 1.6002)
			(stroke
				(width 0.1)
				(type default)
			)
			(layer "B.Fab")
		)
		(fp_line
			(start 0.4953 1.6002)
			(end 0.4953 -0.2032)
			(stroke
				(width 0.1)
				(type default)
			)
			(layer "B.Fab")
		)
		(fp_line
			(start -0.4953 1.6002)
			(end 0.4953 1.6002)
			(stroke
				(width 0.1)
				(type default)
			)
			(layer "B.Fab")
		)
		(pad "1" smd rect
			(at 0 0 270)
			(size 0.762 0.889)
			(layers "B.Cu" "B.Mask" "B.Paste")
			(net "PVDDQ_ABC")
		)
		(pad "2" smd rect
			(at 0 1.397 270)
			(size 0.762 0.889)
			(layers "B.Cu" "B.Mask" "B.Paste")
			(net "GND")
		)
		(zone
			(layer "B.Cu")
			(hatch none 0.5)
			(connect_pads
				(clearance 0)
			)
			(min_thickness 0.25)
			(keepout
				(tracks not_allowed)
				(vias allowed)
				(pads allowed)
				(copperpour not_allowed)
				(footprints allowed)
			)
			(placement
				(enabled no)
				(sheetname "")
			)
			(fill
				(thermal_gap 0.5)
				(thermal_bridge_width 0.5)
				(island_removal_mode 0)
			)
			(polygon
				(pts
					(xy 270.004032 -12.573) (xy 270.512032 -12.573) (xy 270.512032 -13.335) (xy 270.004032 -13.335)
				)
			)
		)
	)
	(footprint ""
		(layer "B.Cu")
		(at 267.081 3.81 90)
		(property "Reference" "C5U15"
			(at 0 0 90)
			(layer "B.SilkS")
			(hide yes)
			(effects
				(font
					(size 1.27 1.27)
				)
				(justify mirror)
			)
		)
		(property "Value" ""
			(at 0 0 90)
			(layer "B.Fab")
			(effects
				(font
					(size 1.27 1.27)
				)
				(justify mirror)
			)
		)
		(duplicate_pad_numbers_are_jumpers no)
		(fp_rect
			(start -0.7239 -0.2159)
			(end 0.7239 1.9939)
			(stroke
				(width 0)
				(type default)
			)
			(fill no)
			(layer "B.CrtYd")
		)
		(fp_line
			(start 0.7239 -0.2159)
			(end 0.7239 1.9939)
			(stroke
				(width 0.1)
				(type default)
			)
			(layer "B.Fab")
		)
		(fp_line
			(start -0.7239 -0.2159)
			(end 0.7239 -0.2159)
			(stroke
				(width 0.1)
				(type default)
			)
			(layer "B.Fab")
		)
		(fp_line
			(start 0.7239 1.9939)
			(end -0.7239 1.9939)
			(stroke
				(width 0.1)
				(type default)
			)
			(layer "B.Fab")
		)
		(fp_line
			(start -0.7239 1.9939)
			(end -0.7239 -0.2159)
			(stroke
				(width 0.1)
				(type default)
			)
			(layer "B.Fab")
		)
		(pad "1" smd rect
			(at 0 0 270)
			(size 1.27 1.016)
			(layers "B.Cu" "B.Mask" "B.Paste")
			(net "PVDDQ_ABC")
		)
		(pad "2" smd rect
			(at 0 1.778 270)
			(size 1.27 1.016)
			(layers "B.Cu" "B.Mask" "B.Paste")
			(net "GND")
		)
		(zone
			(layer "B.Cu")
			(hatch none 0.5)
			(connect_pads
				(clearance 0)
			)
			(min_thickness 0.25)
			(keepout
				(tracks not_allowed)
				(vias allowed)
				(pads allowed)
				(copperpour not_allowed)
				(footprints allowed)
			)
			(placement
				(enabled no)
				(sheetname "")
			)
			(fill
				(thermal_gap 0.5)
				(thermal_bridge_width 0.5)
				(island_removal_mode 0)
			)
			(polygon
				(pts
					(xy 267.589 4.445) (xy 268.351 4.445) (xy 268.351 3.175) (xy 267.589 3.175)
				)
			)
		)
	)
	(footprint ""
		(layer "B.Cu")
		(at 461.1116 -143.0274)
		(property "Reference" "U1L4"
			(at 1.28143 2.50952 270)
			(unlocked yes)
			(layer "B.SilkS")
			(effects
				(font
					(size 0.7874 0.5842)
					(thickness 0.1524)
				)
				(justify left mirror)
			)
		)
		(property "Value" ""
			(at 0 0 0)
			(layer "B.Fab")
			(effects
				(font
					(size 1.27 1.27)
				)
				(justify mirror)
			)
		)
		(duplicate_pad_numbers_are_jumpers no)
		(fp_circle
			(center 0.4699 -0.8382)
			(end 0.5969 -0.8382)
			(stroke
				(width 0.254)
				(type default)
			)
			(fill no)
			(layer "B.SilkS")
		)
		(fp_poly
			(pts
				(xy -0.21463 -0.450088) (xy -1.56337 -0.450088) (xy -1.56337 1.75006) (xy -0.21463 1.75006)
			)
			(stroke
				(width 0)
				(type default)
			)
			(fill no)
			(layer "B.CrtYd")
		)
		(fp_line
			(start -1.56337 -0.450088)
			(end -1.56337 1.75006)
			(stroke
				(width 0.1)
				(type default)
			)
			(layer "B.Fab")
		)
		(fp_line
			(start -1.56337 1.75006)
			(end -0.21463 1.75006)
			(stroke
				(width 0.1)
				(type default)
			)
			(layer "B.Fab")
		)
		(fp_line
			(start -0.21463 -0.450088)
			(end -1.56337 -0.450088)
			(stroke
				(width 0.1)
				(type default)
			)
			(layer "B.Fab")
		)
		(fp_line
			(start -0.21463 1.75006)
			(end -0.21463 -0.450088)
			(stroke
				(width 0.1)
				(type default)
			)
			(layer "B.Fab")
		)
		(fp_circle
			(center 0.4699 -0.8382)
			(end 0.5969 -0.8382)
			(stroke
				(width 0.254)
				(type default)
			)
			(fill no)
			(layer "B.Fab")
		)
		(pad "1" smd rect
			(at 0 0 180)
			(size 1.016 0.381)
			(layers "B.Cu" "B.Mask" "B.Paste")
			(net "Net_6475")
		)
		(pad "2" smd rect
			(at 0 0.649986 180)
			(size 1.016 0.381)
			(layers "B.Cu" "B.Mask" "B.Paste")
			(net "XDP_RST_CO_N")
		)
		(pad "3" smd rect
			(at 0 1.299972 180)
			(size 1.016 0.381)
			(layers "B.Cu" "B.Mask" "B.Paste")
			(net "GND")
		)
		(pad "4" smd rect
			(at -1.778 1.299972 180)
			(size 1.016 0.381)
			(layers "B.Cu" "B.Mask" "B.Paste")
			(net "FM_DEBUG_RST_BTN_R1_N")
		)
		(pad "5" smd rect
			(at -1.778 0 180)
			(size 1.016 0.381)
			(layers "B.Cu" "B.Mask" "B.Paste")
			(net "P3V3_STBY")
		)
	)
	(footprint ""
		(layer "B.Cu")
		(at 333.014574 -120.260364 90)
		(property "Reference" "C4M7"
			(at -0.15367 10.5918 0)
			(unlocked yes)
			(layer "B.SilkS")
			(effects
				(font
					(size 0.7874 0.5842)
					(thickness 0.1524)
				)
				(justify mirror)
			)
		)
		(property "Value" ""
			(at 0 0 90)
			(layer "B.Fab")
			(effects
				(font
					(size 1.27 1.27)
				)
				(justify mirror)
			)
		)
		(duplicate_pad_numbers_are_jumpers no)
		(fp_line
			(start 2.563114 -1.616456)
			(end 2.563114 1.633728)
			(stroke
				(width 0.1524)
				(type default)
			)
			(layer "B.SilkS")
		)
		(fp_line
			(start 1.6002 -1.616456)
			(end 2.563114 -1.616456)
			(stroke
				(width 0.1524)
				(type default)
			)
			(layer "B.SilkS")
		)
		(fp_line
			(start -1.6002 -1.616456)
			(end -2.504948 -1.616456)
			(stroke
				(width 0.1524)
				(type default)
			)
			(layer "B.SilkS")
		)
		(fp_line
			(start -2.504948 -1.616456)
			(end -2.504948 1.633728)
			(stroke
				(width 0.1524)
				(type default)
			)
			(layer "B.SilkS")
		)
		(fp_line
			(start 2.563114 1.633728)
			(end 1.6002 1.633728)
			(stroke
				(width 0.1524)
				(type default)
			)
			(layer "B.SilkS")
		)
		(fp_line
			(start -2.504948 1.633728)
			(end -1.6002 1.633728)
			(stroke
				(width 0.1524)
				(type default)
			)
			(layer "B.SilkS")
		)
		(fp_line
			(start 2.286 7.366)
			(end 2.286 1.632712)
			(stroke
				(width 0.1524)
				(type default)
			)
			(layer "B.SilkS")
		)
		(fp_line
			(start 2.286 7.366)
			(end 1.60147 7.366)
			(stroke
				(width 0.1524)
				(type default)
			)
			(layer "B.SilkS")
		)
		(fp_line
			(start -2.286 7.366)
			(end -2.286 1.63195)
			(stroke
				(width 0.1524)
				(type default)
			)
			(layer "B.SilkS")
		)
		(fp_line
			(start -2.286 7.366)
			(end -1.600708 7.366)
			(stroke
				(width 0.1524)
				(type default)
			)
			(layer "B.SilkS")
		)
		(fp_rect
			(start 2.286 7.366)
			(end -2.286 -0.254)
			(stroke
				(width 0)
				(type default)
			)
			(fill no)
			(layer "B.CrtYd")
		)
		(fp_line
			(start 2.286 -0.254)
			(end -2.286 -0.254)
			(stroke
				(width 0.1)
				(type default)
			)
			(layer "B.Fab")
		)
		(fp_line
			(start -2.286 -0.254)
			(end -2.286 7.366)
			(stroke
				(width 0.1)
				(type default)
			)
			(layer "B.Fab")
		)
		(fp_line
			(start 2.286 7.366)
			(end 2.286 -0.254)
			(stroke
				(width 0.1)
				(type default)
			)
			(layer "B.Fab")
		)
		(fp_line
			(start -2.286 7.366)
			(end 2.286 7.366)
			(stroke
				(width 0.1)
				(type default)
			)
			(layer "B.Fab")
		)
		(pad "1" smd rect
			(at 0 0 270)
			(size 2.54 3.048)
			(layers "B.Cu" "B.Mask" "B.Paste")
			(net "P12V_STBY")
		)
		(pad "2" smd rect
			(at 0 7.112 270)
			(size 2.54 3.048)
			(layers "B.Cu" "B.Mask" "B.Paste")
			(net "GND")
		)
	)
	(footprint ""
		(layer "B.Cu")
		(at 403.8854 2.4384 -90)
		(property "Reference" "C2U28"
			(at 0 0 90)
			(layer "B.SilkS")
			(hide yes)
			(effects
				(font
					(size 1.27 1.27)
				)
				(justify mirror)
			)
		)
		(property "Value" ""
			(at 0 0 90)
			(layer "B.Fab")
			(effects
				(font
					(size 1.27 1.27)
				)
				(justify mirror)
			)
		)
		(duplicate_pad_numbers_are_jumpers no)
		(fp_poly
			(pts
				(xy -0.3048 -0.1016) (xy -0.3048 0.9906) (xy 0.3048 0.9906) (xy 0.3048 -0.1016)
			)
			(stroke
				(width 0)
				(type default)
			)
			(fill no)
			(layer "B.CrtYd")
		)
		(fp_line
			(start -0.3048 0.9906)
			(end -0.3048 -0.1016)
			(stroke
				(width 0.1)
				(type default)
			)
			(layer "B.Fab")
		)
		(fp_line
			(start 0.3048 0.9906)
			(end -0.3048 0.9906)
			(stroke
				(width 0.1)
				(type default)
			)
			(layer "B.Fab")
		)
		(fp_line
			(start -0.3048 -0.1016)
			(end 0.3048 -0.1016)
			(stroke
				(width 0.1)
				(type default)
			)
			(layer "B.Fab")
		)
		(fp_line
			(start 0.3048 -0.1016)
			(end 0.3048 0.9906)
			(stroke
				(width 0.1)
				(type default)
			)
			(layer "B.Fab")
		)
		(pad "1" smd rect
			(at 0 0 90)
			(size 0.508 0.508)
			(layers "B.Cu" "B.Mask" "B.Paste")
			(net "P3V3_STBY")
		)
		(pad "2" smd rect
			(at 0 0.889 90)
			(size 0.508 0.508)
			(layers "B.Cu" "B.Mask" "B.Paste")
			(net "GND")
		)
		(zone
			(layer "B.Cu")
			(hatch none 0.5)
			(connect_pads
				(clearance 0)
			)
			(min_thickness 0.25)
			(keepout
				(tracks not_allowed)
				(vias allowed)
				(pads allowed)
				(copperpour not_allowed)
				(footprints allowed)
			)
			(placement
				(enabled no)
				(sheetname "")
			)
			(fill
				(thermal_gap 0.5)
				(thermal_bridge_width 0.5)
				(island_removal_mode 0)
			)
			(polygon
				(pts
					(xy 403.2504 2.6924) (xy 403.2504 2.1844) (xy 403.6314 2.1844) (xy 403.6314 2.6924)
				)
			)
		)
		(zone
			(layer "B.Cu")
			(hatch none 0.5)
			(connect_pads
				(clearance 0)
			)
			(min_thickness 0.25)
			(keepout
				(tracks allowed)
				(vias not_allowed)
				(pads allowed)
				(copperpour not_allowed)
				(footprints allowed)
			)
			(placement
				(enabled no)
				(sheetname "")
			)
			(fill
				(thermal_gap 0.5)
				(thermal_bridge_width 0.5)
				(island_removal_mode 0)
			)
			(polygon
				(pts
					(xy 403.6314 2.6924) (xy 403.6314 2.1844) (xy 403.2504 2.1844) (xy 403.2504 2.6924)
				)
			)
		)
	)
	(footprint ""
		(layer "B.Cu")
		(at 381.887984 -71.296276 90)
		(property "Reference" "R7E20"
			(at 0 0 90)
			(layer "B.SilkS")
			(hide yes)
			(effects
				(font
					(size 1.27 1.27)
				)
				(justify mirror)
			)
		)
		(property "Value" ""
			(at 0 0 90)
			(layer "B.Fab")
			(effects
				(font
					(size 1.27 1.27)
				)
				(justify mirror)
			)
		)
		(duplicate_pad_numbers_are_jumpers no)
		(fp_poly
			(pts
				(xy 0.2794 -0.1016) (xy -0.2794 -0.1016) (xy -0.2794 0.9906) (xy 0.2794 0.9906)
			)
			(stroke
				(width 0)
				(type default)
			)
			(fill no)
			(layer "B.CrtYd")
		)
		(fp_line
			(start 0.2794 -0.1016)
			(end 0.2794 0.9906)
			(stroke
				(width 0.1)
				(type default)
			)
			(layer "B.Fab")
		)
		(fp_line
			(start -0.2794 -0.1016)
			(end 0.2794 -0.1016)
			(stroke
				(width 0.1)
				(type default)
			)
			(layer "B.Fab")
		)
		(fp_line
			(start 0.2794 0.9906)
			(end -0.2794 0.9906)
			(stroke
				(width 0.1)
				(type default)
			)
			(layer "B.Fab")
		)
		(fp_line
			(start -0.2794 0.9906)
			(end -0.2794 -0.1016)
			(stroke
				(width 0.1)
				(type default)
			)
			(layer "B.Fab")
		)
		(pad "1" smd rect
			(at 0 0 270)
			(size 0.508 0.508)
			(layers "B.Cu" "B.Mask" "B.Paste")
			(net "FM_MEM_EVENT_FUNC")
		)
		(pad "2" smd rect
			(at 0 0.889 270)
			(size 0.508 0.508)
			(layers "B.Cu" "B.Mask" "B.Paste")
			(net "GND")
		)
		(zone
			(layer "B.Cu")
			(hatch none 0.5)
			(connect_pads
				(clearance 0)
			)
			(min_thickness 0.25)
			(keepout
				(tracks allowed)
				(vias not_allowed)
				(pads allowed)
				(copperpour not_allowed)
				(footprints allowed)
			)
			(placement
				(enabled no)
				(sheetname "")
			)
			(fill
				(thermal_gap 0.5)
				(thermal_bridge_width 0.5)
				(island_removal_mode 0)
			)
			(polygon
				(pts
					(xy 382.141984 -71.550276) (xy 382.141984 -71.042276) (xy 382.522984 -71.042276) (xy 382.522984 -71.550276)
				)
			)
		)
		(zone
			(layer "B.Cu")
			(hatch none 0.5)
			(connect_pads
				(clearance 0)
			)
			(min_thickness 0.25)
			(keepout
				(tracks not_allowed)
				(vias allowed)
				(pads allowed)
				(copperpour not_allowed)
				(footprints allowed)
			)
			(placement
				(enabled no)
				(sheetname "")
			)
			(fill
				(thermal_gap 0.5)
				(thermal_bridge_width 0.5)
				(island_removal_mode 0)
			)
			(polygon
				(pts
					(xy 382.522984 -71.550276) (xy 382.522984 -71.042276) (xy 382.141984 -71.042276) (xy 382.141984 -71.550276)
				)
			)
		)
	)
	(footprint ""
		(layer "B.Cu")
		(at 443.865 -64.7446 180)
		(property "Reference" "C2P15"
			(at 0 0 0)
			(layer "B.SilkS")
			(hide yes)
			(effects
				(font
					(size 1.27 1.27)
				)
				(justify mirror)
			)
		)
		(property "Value" ""
			(at 0 0 0)
			(layer "B.Fab")
			(effects
				(font
					(size 1.27 1.27)
				)
				(justify mirror)
			)
		)
		(duplicate_pad_numbers_are_jumpers no)
		(fp_poly
			(pts
				(xy -0.3048 -0.1016) (xy -0.3048 0.9906) (xy 0.3048 0.9906) (xy 0.3048 -0.1016)
			)
			(stroke
				(width 0)
				(type default)
			)
			(fill no)
			(layer "B.CrtYd")
		)
		(fp_line
			(start 0.3048 0.9906)
			(end -0.3048 0.9906)
			(stroke
				(width 0.1)
				(type default)
			)
			(layer "B.Fab")
		)
		(fp_line
			(start 0.3048 -0.1016)
			(end 0.3048 0.9906)
			(stroke
				(width 0.1)
				(type default)
			)
			(layer "B.Fab")
		)
		(fp_line
			(start -0.3048 0.9906)
			(end -0.3048 -0.1016)
			(stroke
				(width 0.1)
				(type default)
			)
			(layer "B.Fab")
		)
		(fp_line
			(start -0.3048 -0.1016)
			(end 0.3048 -0.1016)
			(stroke
				(width 0.1)
				(type default)
			)
			(layer "B.Fab")
		)
		(pad "1" smd rect
			(at 0 0)
			(size 0.508 0.508)
			(layers "B.Cu" "B.Mask" "B.Paste")
			(net "P12V_STBY")
		)
		(pad "2" smd rect
			(at 0 0.889)
			(size 0.508 0.508)
			(layers "B.Cu" "B.Mask" "B.Paste")
			(net "GND")
		)
		(zone
			(layer "B.Cu")
			(hatch none 0.5)
			(connect_pads
				(clearance 0)
			)
			(min_thickness 0.25)
			(keepout
				(tracks not_allowed)
				(vias allowed)
				(pads allowed)
				(copperpour not_allowed)
				(footprints allowed)
			)
			(placement
				(enabled no)
				(sheetname "")
			)
			(fill
				(thermal_gap 0.5)
				(thermal_bridge_width 0.5)
				(island_removal_mode 0)
			)
			(polygon
				(pts
					(xy 443.611 -65.3796) (xy 444.119 -65.3796) (xy 444.119 -64.9986) (xy 443.611 -64.9986)
				)
			)
		)
		(zone
			(layer "B.Cu")
			(hatch none 0.5)
			(connect_pads
				(clearance 0)
			)
			(min_thickness 0.25)
			(keepout
				(tracks allowed)
				(vias not_allowed)
				(pads allowed)
				(copperpour not_allowed)
				(footprints allowed)
			)
			(placement
				(enabled no)
				(sheetname "")
			)
			(fill
				(thermal_gap 0.5)
				(thermal_bridge_width 0.5)
				(island_removal_mode 0)
			)
			(polygon
				(pts
					(xy 443.611 -64.9986) (xy 444.119 -64.9986) (xy 444.119 -65.3796) (xy 443.611 -65.3796)
				)
			)
		)
	)
	(footprint ""
		(layer "B.Cu")
		(at 172.466 -87.757)
		(property "Reference" "R6P2"
			(at 0 0 0)
			(layer "B.SilkS")
			(hide yes)
			(effects
				(font
					(size 1.27 1.27)
				)
				(justify mirror)
			)
		)
		(property "Value" ""
			(at 0 0 0)
			(layer "B.Fab")
			(effects
				(font
					(size 1.27 1.27)
				)
				(justify mirror)
			)
		)
		(duplicate_pad_numbers_are_jumpers no)
		(fp_poly
			(pts
				(xy 0.2794 -0.1016) (xy -0.2794 -0.1016) (xy -0.2794 0.9906) (xy 0.2794 0.9906)
			)
			(stroke
				(width 0)
				(type default)
			)
			(fill no)
			(layer "B.CrtYd")
		)
		(fp_line
			(start -0.2794 -0.1016)
			(end 0.2794 -0.1016)
			(stroke
				(width 0.1)
				(type default)
			)
			(layer "B.Fab")
		)
		(fp_line
			(start -0.2794 0.9906)
			(end -0.2794 -0.1016)
			(stroke
				(width 0.1)
				(type default)
			)
			(layer "B.Fab")
		)
		(fp_line
			(start 0.2794 -0.1016)
			(end 0.2794 0.9906)
			(stroke
				(width 0.1)
				(type default)
			)
			(layer "B.Fab")
		)
		(fp_line
			(start 0.2794 0.9906)
			(end -0.2794 0.9906)
			(stroke
				(width 0.1)
				(type default)
			)
			(layer "B.Fab")
		)
		(pad "1" smd rect
			(at 0 0 180)
			(size 0.508 0.508)
			(layers "B.Cu" "B.Mask" "B.Paste")
			(net "CLK_100M_CPU0_RC_REFCLK0_DN")
		)
		(pad "2" smd rect
			(at 0 0.889 180)
			(size 0.508 0.508)
			(layers "B.Cu" "B.Mask" "B.Paste")
			(net "GND")
		)
		(zone
			(layer "B.Cu")
			(hatch none 0.5)
			(connect_pads
				(clearance 0)
			)
			(min_thickness 0.25)
			(keepout
				(tracks allowed)
				(vias not_allowed)
				(pads allowed)
				(copperpour not_allowed)
				(footprints allowed)
			)
			(placement
				(enabled no)
				(sheetname "")
			)
			(fill
				(thermal_gap 0.5)
				(thermal_bridge_width 0.5)
				(island_removal_mode 0)
			)
			(polygon
				(pts
					(xy 172.72 -87.503) (xy 172.212 -87.503) (xy 172.212 -87.122) (xy 172.72 -87.122)
				)
			)
		)
		(zone
			(layer "B.Cu")
			(hatch none 0.5)
			(connect_pads
				(clearance 0)
			)
			(min_thickness 0.25)
			(keepout
				(tracks not_allowed)
				(vias allowed)
				(pads allowed)
				(copperpour not_allowed)
				(footprints allowed)
			)
			(placement
				(enabled no)
				(sheetname "")
			)
			(fill
				(thermal_gap 0.5)
				(thermal_bridge_width 0.5)
				(island_removal_mode 0)
			)
			(polygon
				(pts
					(xy 172.72 -87.122) (xy 172.212 -87.122) (xy 172.212 -87.503) (xy 172.72 -87.503)
				)
			)
		)
	)
)
